(kicad_pcb
	(version 20241229)
	(generator "pcbnew")
	(generator_version "9.0")
	(general
		(thickness 1.62)
		(legacy_teardrops no)
	)
	(paper "A3")
	(title_block
		(title "COM Express 7 Baseboard")
		(date "2025-02-04")
		(rev "1.1.2")
		(company "Antmicro Ltd")
		(comment 1 "www.antmicro.com")
		(comment 9 "footprints 784-789 of 802")
	)
	(layers
		(0 "F.Cu" signal)
		(4 "In1.Cu" signal)
		(6 "In2.Cu" signal)
		(8 "In3.Cu" signal)
		(10 "In4.Cu" signal)
		(12 "In5.Cu" signal)
		(14 "In6.Cu" signal)
		(2 "B.Cu" signal)
		(9 "F.Adhes" user "F.Adhesive")
		(11 "B.Adhes" user "B.Adhesive")
		(13 "F.Paste" user)
		(15 "B.Paste" user)
		(5 "F.SilkS" user "F.Silkscreen")
		(7 "B.SilkS" user "B.Silkscreen")
		(1 "F.Mask" user)
		(3 "B.Mask" user)
		(17 "Dwgs.User" user "User.Drawings")
		(19 "Cmts.User" user "User.Comments")
		(21 "Eco1.User" user "User.Eco1")
		(23 "Eco2.User" user "User.Eco2")
		(25 "Edge.Cuts" user)
		(27 "Margin" user)
		(31 "F.CrtYd" user "F.Courtyard")
		(29 "B.CrtYd" user "B.Courtyard")
		(35 "F.Fab" user)
		(33 "B.Fab" user)
	)
	(footprint "antmicro-footprints:R_0402_1005Metric"
		(layer "B.Cu")
		(at 198.603122 133.106066 -45)
		(descr "Resistor SMD 0402")
		(tags "resistor SMD 0402")
		(property "Reference" "R217"
			(at 1.259224 -1.324371 135)
			(layer "B.SilkS")
			(effects
				(font
					(size 0.7 0.7)
					(thickness 0.15)
				)
				(justify left top mirror)
			)
		)
		(property "Value" "R_0R_0402"
			(at -1.011843 -1.772046 135)
			(layer "B.Fab")
			(effects
				(font
					(size 0.7 0.7)
					(thickness 0.15)
				)
				(justify left top mirror)
			)
		)
		(property "Datasheet" "https://industrial.panasonic.com/cdbs/www-data/pdf/RDA0000/AOA0000C301.pdf"
			(at 0 0 135)
			(layer "B.Fab")
			(hide yes)
			(effects
				(font
					(size 1.27 1.27)
					(thickness 0.15)
				)
				(justify mirror)
			)
		)
		(property "Author" "Antmicro"
			(at 46.64 -320.56 45)
			(layer "B.Fab")
			(hide yes)
			(effects
				(font
					(size 1 1)
					(thickness 0.15)
				)
				(justify mirror)
			)
		)
		(property "Current" "1A"
			(at 46.64 -320.56 45)
			(layer "B.Fab")
			(hide yes)
			(effects
				(font
					(size 1 1)
					(thickness 0.15)
				)
				(justify mirror)
			)
		)
		(property "License" "Apache-2.0"
			(at 46.64 -320.56 45)
			(layer "B.Fab")
			(hide yes)
			(effects
				(font
					(size 1 1)
					(thickness 0.15)
				)
				(justify mirror)
			)
		)
		(property "MPN" "ERJ2GE0R00X"
			(at 46.64 -320.56 45)
			(layer "B.Fab")
			(hide yes)
			(effects
				(font
					(size 1 1)
					(thickness 0.15)
				)
				(justify mirror)
			)
		)
		(property "Manufacturer" "Panasonic"
			(at 46.64 -320.56 45)
			(layer "B.Fab")
			(hide yes)
			(effects
				(font
					(size 1 1)
					(thickness 0.15)
				)
				(justify mirror)
			)
		)
		(property "Public" "False"
			(at 46.64 -320.56 45)
			(layer "B.Fab")
			(hide yes)
			(effects
				(font
					(size 1 1)
					(thickness 0.15)
				)
				(justify mirror)
			)
		)
		(property "Tolerance" ""
			(at 46.64 -320.56 45)
			(layer "B.Fab")
			(hide yes)
			(effects
				(font
					(size 1 1)
					(thickness 0.15)
				)
				(justify mirror)
			)
		)
		(property "Val" "0R"
			(at 46.64 -320.56 45)
			(layer "B.Fab")
			(hide yes)
			(effects
				(font
					(size 1 1)
					(thickness 0.15)
				)
				(justify mirror)
			)
		)
		(sheetname "PCIe redriver")
		(sheetfile "pcie_redriver.kicad_sch")
		(attr smd)
		(fp_poly
			(pts
				(xy -0.925 0.47) (xy 0.925 0.47) (xy 0.925 -0.47) (xy -0.925 -0.47)
			)
			(stroke
				(width 0.05)
				(type default)
			)
			(fill no)
			(layer "B.CrtYd")
		)
		(fp_poly
			(pts
				(xy -0.5 0.25) (xy 0.5 0.25) (xy 0.5 -0.25) (xy -0.5 -0.25)
			)
			(stroke
				(width 0.15)
				(type solid)
			)
			(fill no)
			(layer "B.Fab")
		)
		(pad "1" smd roundrect
			(at -0.48 0 315)
			(size 0.59 0.64)
			(layers "B.Cu" "B.Mask" "B.Paste")
			(roundrect_rratio 0.25)
			(net 632 "Net-(U40-EN_{I2C})")
			(pintype "passive")
			(teardrops
				(best_length_ratio 0.2)
				(max_length 1)
				(best_width_ratio 0.9)
				(max_width 2)
				(curved_edges yes)
				(filter_ratio 0.9)
				(enabled yes)
				(allow_two_segments yes)
				(prefer_zone_connections yes)
			)
		)
		(pad "2" smd roundrect
			(at 0.48 0 315)
			(size 0.59 0.64)
			(layers "B.Cu" "B.Mask" "B.Paste")
			(roundrect_rratio 0.25)
			(net 1 "GND")
			(pintype "passive")
			(teardrops
				(best_length_ratio 0.2)
				(max_length 1)
				(best_width_ratio 0.9)
				(max_width 2)
				(curved_edges yes)
				(filter_ratio 0.9)
				(enabled yes)
				(allow_two_segments yes)
				(prefer_zone_connections yes)
			)
		)
	)
	(footprint "antmicro-footprints:TP_SMD_0.75mm"
		(layer "B.Cu")
		(at 195.45 163.325 -90)
		(property "Reference" "TP32"
			(at -3.525 0.2 90)
			(layer "B.SilkS")
			(effects
				(font
					(size 0.7 0.7)
					(thickness 0.15)
				)
				(justify left top mirror)
			)
		)
		(property "Value" "TP_0.75mm_SMD"
			(at 0 -1.2 90)
			(layer "B.Fab")
			(effects
				(font
					(size 0.7 0.7)
					(thickness 0.15)
				)
				(justify left top mirror)
			)
		)
		(property "Author" "Antmicro"
			(at 364.61 -51.59 0)
			(layer "B.Fab")
			(hide yes)
			(effects
				(font
					(size 1 1)
					(thickness 0.15)
				)
				(justify mirror)
			)
		)
		(property "License" "Apache-2.0"
			(at 364.61 -51.59 0)
			(layer "B.Fab")
			(hide yes)
			(effects
				(font
					(size 1 1)
					(thickness 0.15)
				)
				(justify mirror)
			)
		)
		(property "MPN" ""
			(at 364.61 -51.59 0)
			(layer "B.Fab")
			(hide yes)
			(effects
				(font
					(size 1 1)
					(thickness 0.15)
				)
				(justify mirror)
			)
		)
		(property "Manufacturer" ""
			(at 364.61 -51.59 0)
			(layer "B.Fab")
			(hide yes)
			(effects
				(font
					(size 1 1)
					(thickness 0.15)
				)
				(justify mirror)
			)
		)
		(property "Public" "False"
			(at 364.61 -51.59 0)
			(layer "B.Fab")
			(hide yes)
			(effects
				(font
					(size 1 1)
					(thickness 0.15)
				)
				(justify mirror)
			)
		)
		(sheetname "Com Express 7 MGMT")
		(sheetfile "com_express_7_mgmt.kicad_sch")
		(attr exclude_from_pos_files exclude_from_bom)
		(fp_circle
			(center 0 0)
			(end 0.475 0)
			(stroke
				(width 0.05)
				(type default)
			)
			(fill no)
			(layer "B.CrtYd")
		)
		(pad "1" smd circle
			(at 0 0 270)
			(size 0.75 0.75)
			(layers "B.Cu" "B.Mask")
			(net 379 "Net-(J12D-~{ESPI_EN})")
			(pinfunction "1")
			(pintype "passive")
			(teardrops
				(best_length_ratio 0.4)
				(max_length 1)
				(best_width_ratio 0.9)
				(max_width 2)
				(curved_edges yes)
				(filter_ratio 0.9)
				(enabled yes)
				(allow_two_segments yes)
				(prefer_zone_connections yes)
			)
		)
	)
	(footprint "antmicro-footprints:C_0402_1005Metric"
		(layer "B.Cu")
		(at 198.12936 140.127637 135)
		(descr "Capacitor SMD 0402")
		(tags "capacitor SMD 0402")
		(property "Reference" "C131"
			(at -3.530586 -0.359976 135)
			(layer "B.SilkS")
			(effects
				(font
					(size 0.7 0.7)
					(thickness 0.15)
				)
				(justify right bottom mirror)
			)
		)
		(property "Value" "C_220n_0402"
			(at -1.022927 -2.155213 135)
			(layer "B.Fab")
			(effects
				(font
					(size 0.7 0.7)
					(thickness 0.15)
				)
				(justify right bottom mirror)
			)
		)
		(property "Datasheet" "https://www.yageo.com/en/Chart/Download/pdf/CC0402KRX5R6BB224"
			(at 0 0 135)
			(layer "F.Fab")
			(hide yes)
			(effects
				(font
					(size 1.27 1.27)
					(thickness 0.15)
				)
			)
		)
		(property "Author" "Antmicro"
			(at 337.3 -40.5 45)
			(layer "B.Fab")
			(hide yes)
			(effects
				(font
					(size 1 1)
					(thickness 0.15)
				)
				(justify mirror)
			)
		)
		(property "Dielectric" ""
			(at 337.3 -40.5 45)
			(layer "B.Fab")
			(hide yes)
			(effects
				(font
					(size 1 1)
					(thickness 0.15)
				)
				(justify mirror)
			)
		)
		(property "License" "Apache-2.0"
			(at 337.3 -40.5 45)
			(layer "B.Fab")
			(hide yes)
			(effects
				(font
					(size 1 1)
					(thickness 0.15)
				)
				(justify mirror)
			)
		)
		(property "MPN" "CC0402KRX5R6BB224"
			(at 337.3 -40.5 45)
			(layer "B.Fab")
			(hide yes)
			(effects
				(font
					(size 1 1)
					(thickness 0.15)
				)
				(justify mirror)
			)
		)
		(property "Manufacturer" "YAGEO"
			(at 337.3 -40.5 45)
			(layer "B.Fab")
			(hide yes)
			(effects
				(font
					(size 1 1)
					(thickness 0.15)
				)
				(justify mirror)
			)
		)
		(property "Public" "False"
			(at 337.3 -40.5 45)
			(layer "B.Fab")
			(hide yes)
			(effects
				(font
					(size 1 1)
					(thickness 0.15)
				)
				(justify mirror)
			)
		)
		(property "Val" "220n"
			(at 337.3 -40.5 45)
			(layer "B.Fab")
			(hide yes)
			(effects
				(font
					(size 1 1)
					(thickness 0.15)
				)
				(justify mirror)
			)
		)
		(property "Voltage" ""
			(at 337.3 -40.5 45)
			(layer "B.Fab")
			(hide yes)
			(effects
				(font
					(size 1 1)
					(thickness 0.15)
				)
				(justify mirror)
			)
		)
		(sheetname "PCIe redriver")
		(sheetfile "pcie_redriver.kicad_sch")
		(attr smd)
		(fp_poly
			(pts
				(xy -0.925 0.47) (xy 0.925 0.47) (xy 0.925 -0.47) (xy -0.925 -0.47)
			)
			(stroke
				(width 0.05)
				(type default)
			)
			(fill no)
			(layer "B.CrtYd")
		)
		(fp_line
			(start 0.504 -0.248)
			(end 0.504 0.25)
			(stroke
				(width 0.15)
				(type solid)
			)
			(layer "B.Fab")
		)
		(fp_line
			(start 0.504 0.25)
			(end -0.494 0.25)
			(stroke
				(width 0.15)
				(type solid)
			)
			(layer "B.Fab")
		)
		(fp_line
			(start -0.494 -0.248)
			(end 0.504 -0.248)
			(stroke
				(width 0.15)
				(type solid)
			)
			(layer "B.Fab")
		)
		(fp_line
			(start -0.494 0.25)
			(end -0.494 -0.248)
			(stroke
				(width 0.15)
				(type solid)
			)
			(layer "B.Fab")
		)
		(pad "1" smd roundrect
			(at -0.48 0 135)
			(size 0.59 0.64)
			(layers "B.Cu" "B.Mask" "B.Paste")
			(roundrect_rratio 0.25)
			(net 218 "/Com Express 7 Interfaces/PCIe_{B1x4}.RX1+")
			(pintype "passive")
			(teardrops
				(best_length_ratio 0.2)
				(max_length 1)
				(best_width_ratio 0.9)
				(max_width 2)
				(curved_edges yes)
				(filter_ratio 0.9)
				(enabled yes)
				(allow_two_segments yes)
				(prefer_zone_connections yes)
			)
		)
		(pad "2" smd roundrect
			(at 0.48 0 135)
			(size 0.59 0.64)
			(layers "B.Cu" "B.Mask" "B.Paste")
			(roundrect_rratio 0.25)
			(net 958 "/PCIe redriver/PCIe_{I}_C.RX1+")
			(pintype "passive")
			(teardrops
				(best_length_ratio 0.2)
				(max_length 1)
				(best_width_ratio 0.9)
				(max_width 2)
				(curved_edges yes)
				(filter_ratio 0.9)
				(enabled yes)
				(allow_two_segments yes)
				(prefer_zone_connections yes)
			)
		)
	)
	(footprint "antmicro-footprints:TP_SMD_0.75mm"
		(layer "B.Cu")
		(at 214.38 124.85 -90)
		(property "Reference" "TP44"
			(at -3.09 -0.52 90)
			(layer "B.SilkS")
			(effects
				(font
					(size 0.7 0.7)
					(thickness 0.15)
				)
				(justify left bottom mirror)
			)
		)
		(property "Value" "TP_0.75mm_SMD"
			(at 0 -1.2 90)
			(layer "B.Fab")
			(effects
				(font
					(size 0.7 0.7)
					(thickness 0.15)
				)
				(justify left bottom mirror)
			)
		)
		(property "Author" "Antmicro"
			(at 89.53 339.23 0)
			(layer "B.Fab")
			(hide yes)
			(effects
				(font
					(size 1 1)
					(thickness 0.15)
				)
				(justify mirror)
			)
		)
		(property "License" "Apache-2.0"
			(at 89.53 339.23 0)
			(layer "B.Fab")
			(hide yes)
			(effects
				(font
					(size 1 1)
					(thickness 0.15)
				)
				(justify mirror)
			)
		)
		(property "MPN" ""
			(at 89.53 339.23 0)
			(layer "B.Fab")
			(hide yes)
			(effects
				(font
					(size 1 1)
					(thickness 0.15)
				)
				(justify mirror)
			)
		)
		(property "Manufacturer" ""
			(at 89.53 339.23 0)
			(layer "B.Fab")
			(hide yes)
			(effects
				(font
					(size 1 1)
					(thickness 0.15)
				)
				(justify mirror)
			)
		)
		(property "Public" "False"
			(at 89.53 339.23 0)
			(layer "B.Fab")
			(hide yes)
			(effects
				(font
					(size 1 1)
					(thickness 0.15)
				)
				(justify mirror)
			)
		)
		(sheetname "PCIe misc")
		(sheetfile "pcie_misc.kicad_sch")
		(attr exclude_from_pos_files exclude_from_bom)
		(fp_circle
			(center 0 0)
			(end 0.475 0)
			(stroke
				(width 0.05)
				(type default)
			)
			(fill no)
			(layer "B.CrtYd")
		)
		(pad "1" smd circle
			(at 0 0 270)
			(size 0.75 0.75)
			(layers "B.Cu" "B.Mask")
			(net 709 "Net-(U37-SCLK)")
			(pinfunction "1")
			(pintype "passive")
			(teardrops
				(best_length_ratio 0.4)
				(max_length 1)
				(best_width_ratio 0.9)
				(max_width 2)
				(curved_edges yes)
				(filter_ratio 0.9)
				(enabled yes)
				(allow_two_segments yes)
				(prefer_zone_connections yes)
			)
		)
	)
	(footprint "antmicro-footprints:R_0402_1005Metric"
		(layer "B.Cu")
		(at 126.09 139.06)
		(descr "Resistor SMD 0402")
		(tags "resistor SMD 0402")
		(property "Reference" "R299"
			(at -3.64 1.2 0)
			(layer "B.SilkS")
			(effects
				(font
					(size 0.7 0.7)
					(thickness 0.15)
				)
				(justify right bottom mirror)
			)
		)
		(property "Value" "R_10k_0402"
			(at -1.011843 -1.772047 0)
			(layer "B.Fab")
			(effects
				(font
					(size 0.7 0.7)
					(thickness 0.15)
				)
				(justify right bottom mirror)
			)
		)
		(property "Datasheet" "https://www.bourns.com/docs/product-datasheets/cr.pdf"
			(at 0 0 0)
			(layer "F.Fab")
			(hide yes)
			(effects
				(font
					(size 1.27 1.27)
					(thickness 0.15)
				)
			)
		)
		(property "Author" "Antmicro"
			(at 0 0 0)
			(layer "B.Fab")
			(hide yes)
			(effects
				(font
					(size 1 1)
					(thickness 0.15)
				)
				(justify mirror)
			)
		)
		(property "License" "Apache-2.0"
			(at 0 0 0)
			(layer "B.Fab")
			(hide yes)
			(effects
				(font
					(size 1 1)
					(thickness 0.15)
				)
				(justify mirror)
			)
		)
		(property "MPN" "CR0402-FX-1002GLF"
			(at 0 0 0)
			(layer "B.Fab")
			(hide yes)
			(effects
				(font
					(size 1 1)
					(thickness 0.15)
				)
				(justify mirror)
			)
		)
		(property "Manufacturer" "Bourns"
			(at 0 0 0)
			(layer "B.Fab")
			(hide yes)
			(effects
				(font
					(size 1 1)
					(thickness 0.15)
				)
				(justify mirror)
			)
		)
		(property "Public" "False"
			(at 0 0 0)
			(layer "B.Fab")
			(hide yes)
			(effects
				(font
					(size 1 1)
					(thickness 0.15)
				)
				(justify mirror)
			)
		)
		(property "Tolerance" "1%"
			(at 0 0 0)
			(layer "B.Fab")
			(hide yes)
			(effects
				(font
					(size 1 1)
					(thickness 0.15)
				)
				(justify mirror)
			)
		)
		(property "Val" "10k"
			(at 0 0 0)
			(layer "B.Fab")
			(hide yes)
			(effects
				(font
					(size 1 1)
					(thickness 0.15)
				)
				(justify mirror)
			)
		)
		(sheetname "KR to SFI #2")
		(sheetfile "kr_sfi.kicad_sch")
		(attr smd)
		(fp_rect
			(start -0.925 0.47)
			(end 0.925 -0.47)
			(stroke
				(width 0.05)
				(type default)
			)
			(fill no)
			(layer "B.CrtYd")
		)
		(fp_rect
			(start -0.5 0.25)
			(end 0.5 -0.25)
			(stroke
				(width 0.15)
				(type solid)
			)
			(fill no)
			(layer "B.Fab")
		)
		(pad "1" smd roundrect
			(at -0.48 0)
			(size 0.59 0.64)
			(layers "B.Cu" "B.Mask" "B.Paste")
			(roundrect_rratio 0.25)
			(net 1 "GND")
			(pintype "passive")
			(teardrops
				(best_length_ratio 0.2)
				(max_length 1)
				(best_width_ratio 0.9)
				(max_width 2)
				(curved_edges yes)
				(filter_ratio 0.9)
				(enabled yes)
				(allow_two_segments yes)
				(prefer_zone_connections yes)
			)
		)
		(pad "2" smd roundrect
			(at 0.48 0)
			(size 0.59 0.64)
			(layers "B.Cu" "B.Mask" "B.Paste")
			(roundrect_rratio 0.25)
			(net 679 "Net-(U45C-PRTAD2)")
			(pintype "passive")
			(teardrops
				(best_length_ratio 0.2)
				(max_length 1)
				(best_width_ratio 0.9)
				(max_width 2)
				(curved_edges yes)
				(filter_ratio 0.9)
				(enabled yes)
				(allow_two_segments yes)
				(prefer_zone_connections yes)
			)
		)
	)
	(footprint "antmicro-footprints:TP_SMD_0.75mm"
		(layer "B.Cu")
		(at 177.35 162.55)
		(property "Reference" "TP30"
			(at 0.65 -0.3 180)
			(layer "B.SilkS")
			(effects
				(font
					(size 0.7 0.7)
					(thickness 0.15)
				)
				(justify right top mirror)
			)
		)
		(property "Value" "TP_0.75mm_SMD"
			(at 3.225 -53.865 0)
			(layer "B.Fab")
			(hide yes)
			(effects
				(font
					(size 0.7 0.7)
					(thickness 0.15)
				)
				(justify right top mirror)
			)
		)
		(property "Author" "Antmicro"
			(at 452.4 308.02 0)
			(layer "B.Fab")
			(hide yes)
			(effects
				(font
					(size 1 1)
					(thickness 0.15)
				)
				(justify mirror)
			)
		)
		(property "License" "Apache-2.0"
			(at 452.4 308.02 0)
			(layer "B.Fab")
			(hide yes)
			(effects
				(font
					(size 1 1)
					(thickness 0.15)
				)
				(justify mirror)
			)
		)
		(property "MPN" ""
			(at 452.4 308.02 0)
			(layer "B.Fab")
			(hide yes)
			(effects
				(font
					(size 1 1)
					(thickness 0.15)
				)
				(justify mirror)
			)
		)
		(property "Manufacturer" ""
			(at 452.4 308.02 0)
			(layer "B.Fab")
			(hide yes)
			(effects
				(font
					(size 1 1)
					(thickness 0.15)
				)
				(justify mirror)
			)
		)
		(property "Public" "False"
			(at 452.4 308.02 0)
			(layer "B.Fab")
			(hide yes)
			(effects
				(font
					(size 1 1)
					(thickness 0.15)
				)
				(justify mirror)
			)
		)
		(sheetname "Com Express 7 MGMT")
		(sheetfile "com_express_7_mgmt.kicad_sch")
		(attr exclude_from_pos_files exclude_from_bom)
		(fp_circle
			(center 0 0)
			(end 0.475 0)
			(stroke
				(width 0.05)
				(type default)
			)
			(fill no)
			(layer "B.CrtYd")
		)
		(pad "1" smd circle
			(at 0 0)
			(size 0.75 0.75)
			(layers "B.Cu" "B.Mask")
			(net 354 "Net-(J12D-~{LPC_DRQ1}{slash}~{ESPI_ALERT1})")
			(pinfunction "1")
			(pintype "passive")
			(teardrops
				(best_length_ratio 0.4)
				(max_length 1)
				(best_width_ratio 0.9)
				(max_width 2)
				(curved_edges yes)
				(filter_ratio 0.9)
				(enabled yes)
				(allow_two_segments yes)
				(prefer_zone_connections yes)
			)
		)
	)
)
